# S9S_MB_2U (Grand Teton) — schematic netlist excerpt (pin names and nets, part order shuffled) for the footprints in the layout excerpt that follows; sources: Cadence DE-HDL packaged netlist, KiCad conversion of 03242023_DA0F0TMBIJ0_F0T_Motherboard_J_brd_V01_OCP.brd

PR1335  Q_RES  0 5% CHIP  pkg 0402LF  page 281 : A = P3V3_AUX ; B = PVPP_HBM_CPU0_VCC
PR3788  Q_RES  15K 1% EMPTY  pkg 0402LF  page 156 : A = P12V_OCP_OV_1 ; B = GND

(kicad_pcb
	(version 20260206)
	(generator "pcbnew")
	(generator_version "10.0")
	(general
		(thickness 1.6)
		(legacy_teardrops no)
	)
	(paper "A4")
	(title_block
		(title "03242023_DA0F0TMBIJ0_F0T_Motherboard_J_brd_V01_OCP.brd")
		(comment 1 "Grand Teton / footprints 3419-3420 of 6105")
	)
	(layers
		(0 "F.Cu" signal "TOP")
		(4 "In1.Cu" signal "GND")
		(6 "In2.Cu" signal "IN1")
		(8 "In3.Cu" signal "GND1")
		(10 "In4.Cu" signal "IN2")
		(12 "In5.Cu" signal "GND2")
		(14 "In6.Cu" signal "IN3")
		(16 "In7.Cu" signal "GND3")
		(18 "In8.Cu" signal "VCC")
		(20 "In9.Cu" signal "VCC1")
		(22 "In10.Cu" signal "GND4")
		(24 "In11.Cu" signal "IN4")
		(26 "In12.Cu" signal "GND5")
		(28 "In13.Cu" signal "IN5")
		(30 "In14.Cu" signal "GND6")
		(32 "In15.Cu" signal "IN6")
		(34 "In16.Cu" signal "GND7")
		(2 "B.Cu" signal "BOTTOM")
		(9 "F.Adhes" user "F.Adhesive")
		(11 "B.Adhes" user "B.Adhesive")
		(13 "F.Paste" user "Package Geometry/Pastemask Top")
		(15 "B.Paste" user "Package Geometry/Pastemask Bottom")
		(5 "F.SilkS" user "Ref Des/Silkscreen Top")
		(7 "B.SilkS" user "Ref Des/Silkscreen Bottom")
		(1 "F.Mask" user "Board Geometry/Soldermask Top")
		(3 "B.Mask" user "Board Geometry/Soldermask Bottom")
		(17 "Dwgs.User" user "User.Drawings")
		(19 "Cmts.User" user "User.Comments")
		(21 "Eco1.User" user "User.Eco1")
		(23 "Eco2.User" user "User.Eco2")
		(25 "Edge.Cuts" user "Board Geometry/Outline")
		(27 "Margin" user)
		(31 "F.CrtYd" user "Package Geometry/Place Bound Top")
		(29 "B.CrtYd" user "Package Geometry/Place Bound Bottom")
		(35 "F.Fab" user "Ref Des/Assembly Top")
		(33 "B.Fab" user "Ref Des/Assembly Bottom")
	)
	(footprint ""
		(layer "F.Cu")
		(at 447.557652 -17.433798 180)
		(property "Reference" "PR3788"
			(at 0 0 180)
			(layer "F.SilkS")
			(hide yes)
			(effects
				(font
					(size 1.27 1.27)
				)
			)
		)
		(property "Value" ""
			(at 0 0 180)
			(layer "F.Fab")
			(effects
				(font
					(size 1.27 1.27)
				)
			)
		)
		(duplicate_pad_numbers_are_jumpers no)
		(fp_line
			(start 0.7874 0.4064)
			(end -0.7874 0.4064)
			(stroke
				(width 0.1524)
				(type default)
			)
			(layer "F.SilkS")
		)
		(fp_line
			(start 0.7874 -0.4064)
			(end 0.7874 0.4064)
			(stroke
				(width 0.1524)
				(type default)
			)
			(layer "F.SilkS")
		)
		(fp_line
			(start -0.7874 0.4064)
			(end -0.7874 -0.4064)
			(stroke
				(width 0.1524)
				(type default)
			)
			(layer "F.SilkS")
		)
		(fp_line
			(start -0.7874 -0.4064)
			(end 0.7874 -0.4064)
			(stroke
				(width 0.1524)
				(type default)
			)
			(layer "F.SilkS")
		)
		(fp_line
			(start 0.67945 0.3048)
			(end 0.120396 0.3048)
			(stroke
				(width 0.1)
				(type default)
			)
			(layer "F.Fab")
		)
		(fp_line
			(start 0.67945 -0.3048)
			(end 0.67945 0.3048)
			(stroke
				(width 0.1)
				(type default)
			)
			(layer "F.Fab")
		)
		(fp_line
			(start 0.12065 -0.2794)
			(end 0.12065 -0.3048)
			(stroke
				(width 0.1)
				(type default)
			)
			(layer "F.Fab")
		)
		(fp_line
			(start 0.12065 -0.3048)
			(end 0.67945 -0.3048)
			(stroke
				(width 0.1)
				(type default)
			)
			(layer "F.Fab")
		)
		(fp_line
			(start 0.120396 0.3048)
			(end 0.120396 0.2794)
			(stroke
				(width 0.1)
				(type default)
			)
			(layer "F.Fab")
		)
		(fp_line
			(start 0.120396 0.2794)
			(end -0.12065 0.2794)
			(stroke
				(width 0.1)
				(type default)
			)
			(layer "F.Fab")
		)
		(fp_line
			(start -0.12065 0.3048)
			(end -0.67945 0.3048)
			(stroke
				(width 0.1)
				(type default)
			)
			(layer "F.Fab")
		)
		(fp_line
			(start -0.12065 0.2794)
			(end -0.12065 0.3048)
			(stroke
				(width 0.1)
				(type default)
			)
			(layer "F.Fab")
		)
		(fp_line
			(start -0.12065 -0.2794)
			(end 0.12065 -0.2794)
			(stroke
				(width 0.1)
				(type default)
			)
			(layer "F.Fab")
		)
		(fp_line
			(start -0.12065 -0.305054)
			(end -0.12065 -0.2794)
			(stroke
				(width 0.1)
				(type default)
			)
			(layer "F.Fab")
		)
		(fp_line
			(start -0.67945 0.3048)
			(end -0.67945 -0.305054)
			(stroke
				(width 0.1)
				(type default)
			)
			(layer "F.Fab")
		)
		(fp_line
			(start -0.67945 -0.305054)
			(end -0.12065 -0.305054)
			(stroke
				(width 0.1)
				(type default)
			)
			(layer "F.Fab")
		)
		(pad "1" smd circle
			(at -0.40005 0 180)
			(size 0 0)
			(layers "F.Cu" "F.Mask" "F.Paste")
			(net "P12V_OCP_OV_1")
		)
		(pad "2" smd circle
			(at 0.40005 0 180)
			(size 0 0)
			(layers "F.Cu" "F.Mask" "F.Paste")
			(net "GND")
		)
	)
	(footprint ""
		(layer "F.Cu")
		(at 376.888248 -361.313476 180)
		(property "Reference" "PR1335"
			(at 0 0 180)
			(layer "F.SilkS")
			(hide yes)
			(effects
				(font
					(size 1.27 1.27)
				)
			)
		)
		(property "Value" ""
			(at 0 0 180)
			(layer "F.Fab")
			(effects
				(font
					(size 1.27 1.27)
				)
			)
		)
		(duplicate_pad_numbers_are_jumpers no)
		(fp_line
			(start 0.7874 0.4064)
			(end -0.7874 0.4064)
			(stroke
				(width 0.1524)
				(type default)
			)
			(layer "F.SilkS")
		)
		(fp_line
			(start 0.7874 -0.4064)
			(end 0.7874 0.4064)
			(stroke
				(width 0.1524)
				(type default)
			)
			(layer "F.SilkS")
		)
		(fp_line
			(start -0.7874 0.4064)
			(end -0.7874 -0.4064)
			(stroke
				(width 0.1524)
				(type default)
			)
			(layer "F.SilkS")
		)
		(fp_line
			(start -0.7874 -0.4064)
			(end 0.7874 -0.4064)
			(stroke
				(width 0.1524)
				(type default)
			)
			(layer "F.SilkS")
		)
		(fp_line
			(start 0.67945 0.3048)
			(end 0.120396 0.3048)
			(stroke
				(width 0.1)
				(type default)
			)
			(layer "F.Fab")
		)
		(fp_line
			(start 0.67945 -0.3048)
			(end 0.67945 0.3048)
			(stroke
				(width 0.1)
				(type default)
			)
			(layer "F.Fab")
		)
		(fp_line
			(start 0.12065 -0.2794)
			(end 0.12065 -0.3048)
			(stroke
				(width 0.1)
				(type default)
			)
			(layer "F.Fab")
		)
		(fp_line
			(start 0.12065 -0.3048)
			(end 0.67945 -0.3048)
			(stroke
				(width 0.1)
				(type default)
			)
			(layer "F.Fab")
		)
		(fp_line
			(start 0.120396 0.3048)
			(end 0.120396 0.2794)
			(stroke
				(width 0.1)
				(type default)
			)
			(layer "F.Fab")
		)
		(fp_line
			(start 0.120396 0.2794)
			(end -0.12065 0.2794)
			(stroke
				(width 0.1)
				(type default)
			)
			(layer "F.Fab")
		)
		(fp_line
			(start -0.12065 0.3048)
			(end -0.67945 0.3048)
			(stroke
				(width 0.1)
				(type default)
			)
			(layer "F.Fab")
		)
		(fp_line
			(start -0.12065 0.2794)
			(end -0.12065 0.3048)
			(stroke
				(width 0.1)
				(type default)
			)
			(layer "F.Fab")
		)
		(fp_line
			(start -0.12065 -0.2794)
			(end 0.12065 -0.2794)
			(stroke
				(width 0.1)
				(type default)
			)
			(layer "F.Fab")
		)
		(fp_line
			(start -0.12065 -0.305054)
			(end -0.12065 -0.2794)
			(stroke
				(width 0.1)
				(type default)
			)
			(layer "F.Fab")
		)
		(fp_line
			(start -0.67945 0.3048)
			(end -0.67945 -0.305054)
			(stroke
				(width 0.1)
				(type default)
			)
			(layer "F.Fab")
		)
		(fp_line
			(start -0.67945 -0.305054)
			(end -0.12065 -0.305054)
			(stroke
				(width 0.1)
				(type default)
			)
			(layer "F.Fab")
		)
		(pad "1" smd circle
			(at -0.40005 0 180)
			(size 0 0)
			(layers "F.Cu" "F.Mask" "F.Paste")
			(net "P3V3_AUX")
		)
		(pad "2" smd circle
			(at 0.40005 0 180)
			(size 0 0)
			(layers "F.Cu" "F.Mask" "F.Paste")
			(net "PVPP_HBM_CPU0_VCC")
		)
	)
)
